(kicad_pcb
	(version 20260206)
	(generator "pcbnew")
	(generator_version "10.0")
	(general
		(thickness 1.6)
		(legacy_teardrops no)
	)
	(paper "A4")
	(title_block
		(title "Bryce Canyon_IOM_IOC_16318-2_OCP.brd")
		(comment 1 "Bryce Canyon / footprints 1116-1122 of 1605")
	)
	(layers
		(0 "F.Cu" signal "TOP")
		(4 "In1.Cu" signal "L2GND")
		(6 "In2.Cu" signal "L3")
		(8 "In3.Cu" signal "L4VCC")
		(10 "In4.Cu" signal "L5VCC")
		(12 "In5.Cu" signal "L6")
		(14 "In6.Cu" signal "L7GND")
		(2 "B.Cu" signal "BOTTOM")
		(9 "F.Adhes" user "F.Adhesive")
		(11 "B.Adhes" user "B.Adhesive")
		(13 "F.Paste" user "Package Geometry/Pastemask Top")
		(15 "B.Paste" user "Package Geometry/Pastemask Bottom")
		(5 "F.SilkS" user "Ref Des/Silkscreen Top")
		(7 "B.SilkS" user "Ref Des/Silkscreen Bottom")
		(1 "F.Mask" user "Board Geometry/Soldermask Top")
		(3 "B.Mask" user "Board Geometry/Soldermask Bottom")
		(17 "Dwgs.User" user "User.Drawings")
		(19 "Cmts.User" user "User.Comments")
		(21 "Eco1.User" user "User.Eco1")
		(23 "Eco2.User" user "User.Eco2")
		(25 "Edge.Cuts" user "Board Geometry/Outline")
		(27 "Margin" user)
		(31 "F.CrtYd" user "Package Geometry/Place Bound Top")
		(29 "B.CrtYd" user "Package Geometry/Place Bound Bottom")
		(35 "F.Fab" user "Ref Des/Assembly Top")
		(33 "B.Fab" user "Ref Des/Assembly Bottom")
	)
	(footprint ""
		(layer "B.Cu")
		(at 67.972686 -149.304502 90)
		(property "Reference" "R386"
			(at 0 0 90)
			(layer "B.SilkS")
			(hide yes)
			(effects
				(font
					(size 1.27 1.27)
				)
				(justify mirror)
			)
		)
		(property "Value" "4K7R2F-GP"
			(at -0.064008 -3.993896 90)
			(unlocked yes)
			(layer "B.Fab")
			(hide yes)
			(effects
				(font
					(size 1.016 1.016)
					(thickness 0.1524)
				)
				(justify mirror)
			)
		)
		(property "Device Type" "R402H16"
			(at -0.064008 -5.517896 90)
			(unlocked yes)
			(layer "B.Fab")
			(hide yes)
			(effects
				(font
					(size 1.016 1.016)
					(thickness 0.1524)
				)
				(justify mirror)
			)
		)
		(duplicate_pad_numbers_are_jumpers no)
		(fp_line
			(start 0.508 -0.9398)
			(end 0.508 0.9398)
			(stroke
				(width 0.1524)
				(type default)
			)
			(layer "B.SilkS")
		)
		(fp_line
			(start -0.508 -0.9398)
			(end 0.508 -0.9398)
			(stroke
				(width 0.1524)
				(type default)
			)
			(layer "B.SilkS")
		)
		(fp_rect
			(start 0.508 0.9398)
			(end -0.508 -0.9398)
			(stroke
				(width 0)
				(type default)
			)
			(fill no)
			(layer "B.CrtYd")
		)
		(fp_rect
			(start 0.508 0.9398)
			(end -0.508 -0.9398)
			(stroke
				(width 0)
				(type default)
			)
			(fill no)
			(layer "B.Fab")
		)
		(pad "1" smd custom
			(at 0 -0.4445 270)
			(size 0.1397 0.1397)
			(layers "B.Cu" "B.Mask" "B.Paste")
			(net "GND")
			(options
				(clearance outline)
				(anchor circle)
			)
			(primitives
				(gr_poly
					(pts
						(arc
							(start -0.1778 0.2794)
							(mid -0.249642 0.249642)
							(end -0.2794 0.1778)
						)
						(arc
							(start -0.2794 -0.1778)
							(mid -0.249642 -0.249642)
							(end -0.1778 -0.2794)
						)
						(arc
							(start 0.1778 -0.2794)
							(mid 0.249642 -0.249642)
							(end 0.2794 -0.1778)
						)
						(arc
							(start 0.2794 0.1778)
							(mid 0.249642 0.249642)
							(end 0.1778 0.2794)
						)
					)
					(width 0)
					(fill yes)
				)
			)
		)
		(pad "2" smd custom
			(at 0 0.4445 270)
			(size 0.1397 0.1397)
			(layers "B.Cu" "B.Mask" "B.Paste")
			(net "NCSI_TXD0")
			(options
				(clearance outline)
				(anchor circle)
			)
			(primitives
				(gr_poly
					(pts
						(arc
							(start -0.1778 0.2794)
							(mid -0.249642 0.249642)
							(end -0.2794 0.1778)
						)
						(arc
							(start -0.2794 -0.1778)
							(mid -0.249642 -0.249642)
							(end -0.1778 -0.2794)
						)
						(arc
							(start 0.1778 -0.2794)
							(mid 0.249642 -0.249642)
							(end 0.2794 -0.1778)
						)
						(arc
							(start 0.2794 0.1778)
							(mid 0.249642 0.249642)
							(end 0.1778 0.2794)
						)
					)
					(width 0)
					(fill yes)
				)
			)
		)
	)
	(footprint ""
		(layer "B.Cu")
		(at 115.9256 -14.2494)
		(property "Reference" "R741"
			(at 0 0 0)
			(layer "B.SilkS")
			(hide yes)
			(effects
				(font
					(size 1.27 1.27)
				)
				(justify mirror)
			)
		)
		(property "Value" "0R2J-2-GP"
			(at -0.064008 -3.993896 0)
			(unlocked yes)
			(layer "B.Fab")
			(hide yes)
			(effects
				(font
					(size 1.016 1.016)
					(thickness 0.1524)
				)
				(justify mirror)
			)
		)
		(property "Device Type" "R402H16"
			(at -0.064008 -5.517896 0)
			(unlocked yes)
			(layer "B.Fab")
			(hide yes)
			(effects
				(font
					(size 1.016 1.016)
					(thickness 0.1524)
				)
				(justify mirror)
			)
		)
		(duplicate_pad_numbers_are_jumpers no)
		(fp_line
			(start -0.508 -0.9398)
			(end 0.508 -0.9398)
			(stroke
				(width 0.1524)
				(type default)
			)
			(layer "B.SilkS")
		)
		(fp_line
			(start 0.508 -0.9398)
			(end 0.508 0.9398)
			(stroke
				(width 0.1524)
				(type default)
			)
			(layer "B.SilkS")
		)
		(fp_rect
			(start 0.508 0.9398)
			(end -0.508 -0.9398)
			(stroke
				(width 0)
				(type default)
			)
			(fill no)
			(layer "B.CrtYd")
		)
		(fp_rect
			(start 0.508 0.9398)
			(end -0.508 -0.9398)
			(stroke
				(width 0)
				(type default)
			)
			(fill no)
			(layer "B.Fab")
		)
		(pad "1" smd custom
			(at 0 -0.4445 180)
			(size 0.1397 0.1397)
			(layers "B.Cu" "B.Mask" "B.Paste")
			(net "IOM_ADM1278_EN")
			(options
				(clearance outline)
				(anchor circle)
			)
			(primitives
				(gr_poly
					(pts
						(arc
							(start -0.1778 0.2794)
							(mid -0.249642 0.249642)
							(end -0.2794 0.1778)
						)
						(arc
							(start -0.2794 -0.1778)
							(mid -0.249642 -0.249642)
							(end -0.1778 -0.2794)
						)
						(arc
							(start 0.1778 -0.2794)
							(mid 0.249642 -0.249642)
							(end 0.2794 -0.1778)
						)
						(arc
							(start 0.2794 0.1778)
							(mid 0.249642 0.249642)
							(end 0.1778 0.2794)
						)
					)
					(width 0)
					(fill yes)
				)
			)
		)
		(pad "2" smd custom
			(at 0 0.4445 180)
			(size 0.1397 0.1397)
			(layers "B.Cu" "B.Mask" "B.Paste")
			(net "MB0_HS_ENABLE")
			(options
				(clearance outline)
				(anchor circle)
			)
			(primitives
				(gr_poly
					(pts
						(arc
							(start -0.1778 0.2794)
							(mid -0.249642 0.249642)
							(end -0.2794 0.1778)
						)
						(arc
							(start -0.2794 -0.1778)
							(mid -0.249642 -0.249642)
							(end -0.1778 -0.2794)
						)
						(arc
							(start 0.1778 -0.2794)
							(mid 0.249642 -0.249642)
							(end 0.2794 -0.1778)
						)
						(arc
							(start 0.2794 0.1778)
							(mid 0.249642 0.249642)
							(end 0.1778 0.2794)
						)
					)
					(width 0)
					(fill yes)
				)
			)
		)
	)
	(footprint ""
		(layer "B.Cu")
		(at 193.9798 -61.6204 90)
		(property "Reference" "C420"
			(at 0 0 90)
			(layer "B.SilkS")
			(hide yes)
			(effects
				(font
					(size 1.27 1.27)
				)
				(justify mirror)
			)
		)
		(property "Value" "SCD1U6D3V1KX-GP"
			(at 2.8321 -1.7399 90)
			(unlocked yes)
			(layer "B.Fab")
			(hide yes)
			(effects
				(font
					(size 1.016 1.016)
					(thickness 0.1524)
				)
				(justify mirror)
			)
		)
		(property "Device Type" "C0201H13"
			(at 2.8321 -3.2639 90)
			(unlocked yes)
			(layer "B.Fab")
			(hide yes)
			(effects
				(font
					(size 1.016 1.016)
					(thickness 0.1524)
				)
				(justify mirror)
			)
		)
		(duplicate_pad_numbers_are_jumpers no)
		(fp_rect
			(start 0.2794 0.6477)
			(end -0.2794 -0.6477)
			(stroke
				(width 0)
				(type default)
			)
			(fill no)
			(layer "B.CrtYd")
		)
		(fp_rect
			(start 0.2794 0.6477)
			(end -0.2794 -0.6477)
			(stroke
				(width 0)
				(type default)
			)
			(fill no)
			(layer "B.Fab")
		)
		(pad "1" smd custom
			(at 0 -0.2794 270)
			(size 0.0762 0.0762)
			(layers "B.Cu" "B.Mask" "B.Paste")
			(net "P0V975")
			(options
				(clearance outline)
				(anchor circle)
			)
			(primitives
				(gr_poly
					(pts
						(arc
							(start 0.1524 0.127)
							(mid 0.137521 0.162921)
							(end 0.1016 0.1778)
						)
						(arc
							(start -0.1016 0.1778)
							(mid -0.137521 0.162921)
							(end -0.1524 0.127)
						)
						(arc
							(start -0.1524 -0.127)
							(mid -0.137521 -0.162921)
							(end -0.1016 -0.1778)
						)
						(arc
							(start 0.1016 -0.1778)
							(mid 0.137521 -0.162921)
							(end 0.1524 -0.127)
						)
					)
					(width 0)
					(fill yes)
				)
			)
		)
		(pad "2" smd custom
			(at 0 0.2794 270)
			(size 0.0762 0.0762)
			(layers "B.Cu" "B.Mask" "B.Paste")
			(net "GND")
			(options
				(clearance outline)
				(anchor circle)
			)
			(primitives
				(gr_poly
					(pts
						(arc
							(start 0.1524 0.127)
							(mid 0.137521 0.162921)
							(end 0.1016 0.1778)
						)
						(arc
							(start -0.1016 0.1778)
							(mid -0.137521 0.162921)
							(end -0.1524 0.127)
						)
						(arc
							(start -0.1524 -0.127)
							(mid -0.137521 -0.162921)
							(end -0.1016 -0.1778)
						)
						(arc
							(start 0.1016 -0.1778)
							(mid 0.137521 -0.162921)
							(end 0.1524 -0.127)
						)
					)
					(width 0)
					(fill yes)
				)
			)
		)
	)
	(footprint ""
		(layer "B.Cu")
		(at 88.692228 -96.411796 180)
		(property "Reference" "R728"
			(at 0 0 0)
			(layer "B.SilkS")
			(hide yes)
			(effects
				(font
					(size 1.27 1.27)
				)
				(justify mirror)
			)
		)
		(property "Value" "4K7R2F-GP"
			(at -0.064008 -3.993896 180)
			(unlocked yes)
			(layer "B.Fab")
			(hide yes)
			(effects
				(font
					(size 1.016 1.016)
					(thickness 0.1524)
				)
				(justify mirror)
			)
		)
		(property "Device Type" "R402H16"
			(at -0.064008 -5.517896 180)
			(unlocked yes)
			(layer "B.Fab")
			(hide yes)
			(effects
				(font
					(size 1.016 1.016)
					(thickness 0.1524)
				)
				(justify mirror)
			)
		)
		(duplicate_pad_numbers_are_jumpers no)
		(fp_line
			(start 0.508 -0.9398)
			(end 0.508 0.9398)
			(stroke
				(width 0.1524)
				(type default)
			)
			(layer "B.SilkS")
		)
		(fp_line
			(start -0.508 -0.9398)
			(end 0.508 -0.9398)
			(stroke
				(width 0.1524)
				(type default)
			)
			(layer "B.SilkS")
		)
		(fp_rect
			(start 0.508 0.9398)
			(end -0.508 -0.9398)
			(stroke
				(width 0)
				(type default)
			)
			(fill no)
			(layer "B.CrtYd")
		)
		(fp_rect
			(start 0.508 0.9398)
			(end -0.508 -0.9398)
			(stroke
				(width 0)
				(type default)
			)
			(fill no)
			(layer "B.Fab")
		)
		(pad "1" smd custom
			(at 0 -0.4445)
			(size 0.1397 0.1397)
			(layers "B.Cu" "B.Mask" "B.Paste")
			(net "CONN_A_PRSNTA")
			(options
				(clearance outline)
				(anchor circle)
			)
			(primitives
				(gr_poly
					(pts
						(arc
							(start -0.1778 0.2794)
							(mid -0.249642 0.249642)
							(end -0.2794 0.1778)
						)
						(arc
							(start -0.2794 -0.1778)
							(mid -0.249642 -0.249642)
							(end -0.1778 -0.2794)
						)
						(arc
							(start 0.1778 -0.2794)
							(mid 0.249642 -0.249642)
							(end 0.2794 -0.1778)
						)
						(arc
							(start 0.2794 0.1778)
							(mid 0.249642 0.249642)
							(end 0.1778 0.2794)
						)
					)
					(width 0)
					(fill yes)
				)
			)
		)
		(pad "2" smd custom
			(at 0 0.4445)
			(size 0.1397 0.1397)
			(layers "B.Cu" "B.Mask" "B.Paste")
			(net "P3V3_STBY")
			(options
				(clearance outline)
				(anchor circle)
			)
			(primitives
				(gr_poly
					(pts
						(arc
							(start -0.1778 0.2794)
							(mid -0.249642 0.249642)
							(end -0.2794 0.1778)
						)
						(arc
							(start -0.2794 -0.1778)
							(mid -0.249642 -0.249642)
							(end -0.1778 -0.2794)
						)
						(arc
							(start 0.1778 -0.2794)
							(mid 0.249642 -0.249642)
							(end 0.2794 -0.1778)
						)
						(arc
							(start 0.2794 0.1778)
							(mid 0.249642 0.249642)
							(end 0.1778 0.2794)
						)
					)
					(width 0)
					(fill yes)
				)
			)
		)
	)
	(footprint ""
		(layer "B.Cu")
		(at 206.7814 -56.9468 180)
		(property "Reference" "R593"
			(at 0 0 0)
			(layer "B.SilkS")
			(hide yes)
			(effects
				(font
					(size 1.27 1.27)
				)
				(justify mirror)
			)
		)
		(property "Value" "2K2R2F-GP"
			(at -0.064008 -3.993896 180)
			(unlocked yes)
			(layer "B.Fab")
			(hide yes)
			(effects
				(font
					(size 1.016 1.016)
					(thickness 0.1524)
				)
				(justify mirror)
			)
		)
		(property "Device Type" "R402H16"
			(at -0.064008 -5.517896 180)
			(unlocked yes)
			(layer "B.Fab")
			(hide yes)
			(effects
				(font
					(size 1.016 1.016)
					(thickness 0.1524)
				)
				(justify mirror)
			)
		)
		(duplicate_pad_numbers_are_jumpers no)
		(fp_line
			(start 0.508 -0.9398)
			(end 0.508 0.9398)
			(stroke
				(width 0.1524)
				(type default)
			)
			(layer "B.SilkS")
		)
		(fp_line
			(start -0.508 -0.9398)
			(end 0.508 -0.9398)
			(stroke
				(width 0.1524)
				(type default)
			)
			(layer "B.SilkS")
		)
		(fp_rect
			(start 0.508 0.9398)
			(end -0.508 -0.9398)
			(stroke
				(width 0)
				(type default)
			)
			(fill no)
			(layer "B.CrtYd")
		)
		(fp_rect
			(start 0.508 0.9398)
			(end -0.508 -0.9398)
			(stroke
				(width 0)
				(type default)
			)
			(fill no)
			(layer "B.Fab")
		)
		(pad "1" smd custom
			(at 0 -0.4445)
			(size 0.1397 0.1397)
			(layers "B.Cu" "B.Mask" "B.Paste")
			(net "P1V8")
			(options
				(clearance outline)
				(anchor circle)
			)
			(primitives
				(gr_poly
					(pts
						(arc
							(start -0.1778 0.2794)
							(mid -0.249642 0.249642)
							(end -0.2794 0.1778)
						)
						(arc
							(start -0.2794 -0.1778)
							(mid -0.249642 -0.249642)
							(end -0.1778 -0.2794)
						)
						(arc
							(start 0.1778 -0.2794)
							(mid 0.249642 -0.249642)
							(end 0.2794 -0.1778)
						)
						(arc
							(start 0.2794 0.1778)
							(mid 0.249642 0.249642)
							(end 0.1778 0.2794)
						)
					)
					(width 0)
					(fill yes)
				)
			)
		)
		(pad "2" smd custom
			(at 0 0.4445)
			(size 0.1397 0.1397)
			(layers "B.Cu" "B.Mask" "B.Paste")
			(net "SIO_DIN_1")
			(options
				(clearance outline)
				(anchor circle)
			)
			(primitives
				(gr_poly
					(pts
						(arc
							(start -0.1778 0.2794)
							(mid -0.249642 0.249642)
							(end -0.2794 0.1778)
						)
						(arc
							(start -0.2794 -0.1778)
							(mid -0.249642 -0.249642)
							(end -0.1778 -0.2794)
						)
						(arc
							(start 0.1778 -0.2794)
							(mid 0.249642 -0.249642)
							(end 0.2794 -0.1778)
						)
						(arc
							(start 0.2794 0.1778)
							(mid 0.249642 0.249642)
							(end 0.1778 0.2794)
						)
					)
					(width 0)
					(fill yes)
				)
			)
		)
	)
	(footprint ""
		(layer "B.Cu")
		(at 92.8116 -145.8976)
		(property "Reference" "R425"
			(at 0 0 0)
			(layer "B.SilkS")
			(hide yes)
			(effects
				(font
					(size 1.27 1.27)
				)
				(justify mirror)
			)
		)
		(property "Value" "4K7R2F-GP"
			(at -0.064008 -3.993896 0)
			(unlocked yes)
			(layer "B.Fab")
			(hide yes)
			(effects
				(font
					(size 1.016 1.016)
					(thickness 0.1524)
				)
				(justify mirror)
			)
		)
		(property "Device Type" "R402H16"
			(at -0.064008 -5.517896 0)
			(unlocked yes)
			(layer "B.Fab")
			(hide yes)
			(effects
				(font
					(size 1.016 1.016)
					(thickness 0.1524)
				)
				(justify mirror)
			)
		)
		(duplicate_pad_numbers_are_jumpers no)
		(fp_line
			(start -0.508 -0.9398)
			(end 0.508 -0.9398)
			(stroke
				(width 0.1524)
				(type default)
			)
			(layer "B.SilkS")
		)
		(fp_line
			(start 0.508 -0.9398)
			(end 0.508 0.9398)
			(stroke
				(width 0.1524)
				(type default)
			)
			(layer "B.SilkS")
		)
		(fp_rect
			(start 0.508 0.9398)
			(end -0.508 -0.9398)
			(stroke
				(width 0)
				(type default)
			)
			(fill no)
			(layer "B.CrtYd")
		)
		(fp_rect
			(start 0.508 0.9398)
			(end -0.508 -0.9398)
			(stroke
				(width 0)
				(type default)
			)
			(fill no)
			(layer "B.Fab")
		)
		(pad "1" smd custom
			(at 0 -0.4445 180)
			(size 0.1397 0.1397)
			(layers "B.Cu" "B.Mask" "B.Paste")
			(net "P3V3_STBY")
			(options
				(clearance outline)
				(anchor circle)
			)
			(primitives
				(gr_poly
					(pts
						(arc
							(start -0.1778 0.2794)
							(mid -0.249642 0.249642)
							(end -0.2794 0.1778)
						)
						(arc
							(start -0.2794 -0.1778)
							(mid -0.249642 -0.249642)
							(end -0.1778 -0.2794)
						)
						(arc
							(start 0.1778 -0.2794)
							(mid 0.249642 -0.249642)
							(end 0.2794 -0.1778)
						)
						(arc
							(start 0.2794 0.1778)
							(mid 0.249642 0.249642)
							(end 0.1778 0.2794)
						)
					)
					(width 0)
					(fill yes)
				)
			)
		)
		(pad "2" smd custom
			(at 0 0.4445 180)
			(size 0.1397 0.1397)
			(layers "B.Cu" "B.Mask" "B.Paste")
			(net "TCA9555_A2")
			(options
				(clearance outline)
				(anchor circle)
			)
			(primitives
				(gr_poly
					(pts
						(arc
							(start -0.1778 0.2794)
							(mid -0.249642 0.249642)
							(end -0.2794 0.1778)
						)
						(arc
							(start -0.2794 -0.1778)
							(mid -0.249642 -0.249642)
							(end -0.1778 -0.2794)
						)
						(arc
							(start 0.1778 -0.2794)
							(mid 0.249642 -0.249642)
							(end 0.2794 -0.1778)
						)
						(arc
							(start 0.2794 0.1778)
							(mid 0.249642 0.249642)
							(end 0.1778 0.2794)
						)
					)
					(width 0)
					(fill yes)
				)
			)
		)
	)
	(footprint ""
		(layer "B.Cu")
		(at 187.9854 -55.5752 90)
		(property "Reference" "C432"
			(at 0 0 90)
			(layer "B.SilkS")
			(hide yes)
			(effects
				(font
					(size 1.27 1.27)
				)
				(justify mirror)
			)
		)
		(property "Value" "SCD1U16V2KX-3GP"
			(at -1.1811 -2.7051 90)
			(unlocked yes)
			(layer "B.Fab")
			(hide yes)
			(effects
				(font
					(size 1.016 1.016)
					(thickness 0.1524)
				)
				(justify mirror)
			)
		)
		(property "Device Type" "C402H22"
			(at -1.1811 -4.2291 90)
			(unlocked yes)
			(layer "B.Fab")
			(hide yes)
			(effects
				(font
					(size 1.016 1.016)
					(thickness 0.1524)
				)
				(justify mirror)
			)
		)
		(duplicate_pad_numbers_are_jumpers no)
		(fp_rect
			(start 0.4318 0.9525)
			(end -0.4318 -0.9525)
			(stroke
				(width 0)
				(type default)
			)
			(fill no)
			(layer "B.CrtYd")
		)
		(fp_rect
			(start 0.4318 0.9525)
			(end -0.4318 -0.9525)
			(stroke
				(width 0)
				(type default)
			)
			(fill no)
			(layer "B.Fab")
		)
		(pad "1" smd custom
			(at 0 -0.4445 270)
			(size 0.1524 0.1524)
			(layers "B.Cu" "B.Mask" "B.Paste")
			(net "P1V8")
			(options
				(clearance outline)
				(anchor circle)
			)
			(primitives
				(gr_poly
					(pts
						(arc
							(start 0.3048 0.2032)
							(mid 0.275042 0.275042)
							(end 0.2032 0.3048)
						)
						(arc
							(start -0.2032 0.3048)
							(mid -0.275042 0.275042)
							(end -0.3048 0.2032)
						)
						(arc
							(start -0.3048 -0.2032)
							(mid -0.275042 -0.275042)
							(end -0.2032 -0.3048)
						)
						(arc
							(start 0.2032 -0.3048)
							(mid 0.275042 -0.275042)
							(end 0.3048 -0.2032)
						)
					)
					(width 0)
					(fill yes)
				)
			)
		)
		(pad "2" smd custom
			(at 0 0.4445 270)
			(size 0.1524 0.1524)
			(layers "B.Cu" "B.Mask" "B.Paste")
			(net "GND")
			(options
				(clearance outline)
				(anchor circle)
			)
			(primitives
				(gr_poly
					(pts
						(arc
							(start 0.3048 0.2032)
							(mid 0.275042 0.275042)
							(end 0.2032 0.3048)
						)
						(arc
							(start -0.2032 0.3048)
							(mid -0.275042 0.275042)
							(end -0.3048 0.2032)
						)
						(arc
							(start -0.3048 -0.2032)
							(mid -0.275042 -0.275042)
							(end -0.2032 -0.3048)
						)
						(arc
							(start 0.2032 -0.3048)
							(mid 0.275042 -0.275042)
							(end 0.3048 -0.2032)
						)
					)
					(width 0)
					(fill yes)
				)
			)
		)
	)
)
